(kicad_pcb
	(version 20260206)
	(generator "pcbnew")
	(generator_version "10.0")
	(general
		(thickness 1.6)
		(legacy_teardrops no)
	)
	(paper "A4")
	(title_block
		(title "01162023_DA0F0TEBIF0_F0T_Expander_BD_F_brd_V02_OCP.brd")
		(comment 1 "Grand Teton / footprints 677-684 of 9728")
	)
	(layers
		(0 "F.Cu" signal "TOP")
		(4 "In1.Cu" signal "GND")
		(6 "In2.Cu" signal "VCC")
		(8 "In3.Cu" signal "VCC1")
		(10 "In4.Cu" signal "GND1")
		(12 "In5.Cu" signal "IN1")
		(14 "In6.Cu" signal "GND2")
		(16 "In7.Cu" signal "IN2")
		(18 "In8.Cu" signal "GND3")
		(20 "In9.Cu" signal "IN3")
		(22 "In10.Cu" signal "GND4")
		(24 "In11.Cu" signal "IN4")
		(26 "In12.Cu" signal "GND5")
		(28 "In13.Cu" signal "IN5")
		(30 "In14.Cu" signal "GND6")
		(32 "In15.Cu" signal "IN6")
		(34 "In16.Cu" signal "GND7")
		(2 "B.Cu" signal "BOTTOM")
		(9 "F.Adhes" user "F.Adhesive")
		(11 "B.Adhes" user "B.Adhesive")
		(13 "F.Paste" user "Package Geometry/Pastemask Top")
		(15 "B.Paste" user "Package Geometry/Pastemask Bottom")
		(5 "F.SilkS" user "Ref Des/Silkscreen Top")
		(7 "B.SilkS" user "Ref Des/Silkscreen Bottom")
		(1 "F.Mask" user "Board Geometry/Soldermask Top")
		(3 "B.Mask" user "Board Geometry/Soldermask Bottom")
		(17 "Dwgs.User" user "User.Drawings")
		(19 "Cmts.User" user "User.Comments")
		(21 "Eco1.User" user "User.Eco1")
		(23 "Eco2.User" user "User.Eco2")
		(25 "Edge.Cuts" user "Board Geometry/Outline")
		(27 "Margin" user)
		(31 "F.CrtYd" user "Package Geometry/Place Bound Top")
		(29 "B.CrtYd" user "Package Geometry/Place Bound Bottom")
		(35 "F.Fab" user "Ref Des/Assembly Top")
		(33 "B.Fab" user "Ref Des/Assembly Bottom")
	)
	(footprint ""
		(layer "F.Cu")
		(at 493.02416 -525.811496)
		(property "Reference" "SCREW_9"
			(at -0.5842 -1.31953 0)
			(unlocked yes)
			(layer "B.SilkS")
			(effects
				(font
					(size 0.7874 0.5842)
					(thickness 0.1524)
				)
				(justify left mirror)
			)
		)
		(property "Value" ""
			(at 0 0 0)
			(layer "F.Fab")
			(effects
				(font
					(size 1.27 1.27)
				)
			)
		)
		(duplicate_pad_numbers_are_jumpers no)
		(pad "1" thru_hole circle
			(at 0 0)
			(size 0.4572 0.4572)
			(drill 0.2032)
			(layers "*.Cu" "*.Mask")
			(remove_unused_layers no)
			(net "Net_9328")
			(clearance 0.127)
			(thermal_gap 0.127)
			(padstack
				(mode front_inner_back)
				(layer "Inner"
					(shape circle)
					(size 0.4572 0.4572)
					(clearance 0.127)
				)
				(layer "B.Cu"
					(shape circle)
					(size 0.508 0.508)
					(clearance 0.1016)
				)
			)
		)
	)
	(footprint ""
		(layer "F.Cu")
		(at 301.138336 -82.332068 180)
		(property "Reference" "R488"
			(at 0 0 180)
			(layer "F.SilkS")
			(hide yes)
			(effects
				(font
					(size 1.27 1.27)
				)
			)
		)
		(property "Value" ""
			(at 0 0 180)
			(layer "F.Fab")
			(effects
				(font
					(size 1.27 1.27)
				)
			)
		)
		(duplicate_pad_numbers_are_jumpers no)
		(fp_line
			(start 0.7874 0.4064)
			(end -0.7874 0.4064)
			(stroke
				(width 0.1524)
				(type default)
			)
			(layer "F.SilkS")
		)
		(fp_line
			(start 0.7874 -0.4064)
			(end 0.7874 0.4064)
			(stroke
				(width 0.1524)
				(type default)
			)
			(layer "F.SilkS")
		)
		(fp_line
			(start -0.7874 0.4064)
			(end -0.7874 -0.4064)
			(stroke
				(width 0.1524)
				(type default)
			)
			(layer "F.SilkS")
		)
		(fp_line
			(start -0.7874 -0.4064)
			(end 0.7874 -0.4064)
			(stroke
				(width 0.1524)
				(type default)
			)
			(layer "F.SilkS")
		)
		(fp_line
			(start 0.67945 0.3048)
			(end 0.120396 0.3048)
			(stroke
				(width 0.1)
				(type default)
			)
			(layer "F.Fab")
		)
		(fp_line
			(start 0.67945 -0.3048)
			(end 0.67945 0.3048)
			(stroke
				(width 0.1)
				(type default)
			)
			(layer "F.Fab")
		)
		(fp_line
			(start 0.12065 -0.2794)
			(end 0.12065 -0.3048)
			(stroke
				(width 0.1)
				(type default)
			)
			(layer "F.Fab")
		)
		(fp_line
			(start 0.12065 -0.3048)
			(end 0.67945 -0.3048)
			(stroke
				(width 0.1)
				(type default)
			)
			(layer "F.Fab")
		)
		(fp_line
			(start 0.120396 0.3048)
			(end 0.120396 0.2794)
			(stroke
				(width 0.1)
				(type default)
			)
			(layer "F.Fab")
		)
		(fp_line
			(start 0.120396 0.2794)
			(end -0.12065 0.2794)
			(stroke
				(width 0.1)
				(type default)
			)
			(layer "F.Fab")
		)
		(fp_line
			(start -0.12065 0.3048)
			(end -0.67945 0.3048)
			(stroke
				(width 0.1)
				(type default)
			)
			(layer "F.Fab")
		)
		(fp_line
			(start -0.12065 0.2794)
			(end -0.12065 0.3048)
			(stroke
				(width 0.1)
				(type default)
			)
			(layer "F.Fab")
		)
		(fp_line
			(start -0.12065 -0.2794)
			(end 0.12065 -0.2794)
			(stroke
				(width 0.1)
				(type default)
			)
			(layer "F.Fab")
		)
		(fp_line
			(start -0.12065 -0.305054)
			(end -0.12065 -0.2794)
			(stroke
				(width 0.1)
				(type default)
			)
			(layer "F.Fab")
		)
		(fp_line
			(start -0.67945 0.3048)
			(end -0.67945 -0.305054)
			(stroke
				(width 0.1)
				(type default)
			)
			(layer "F.Fab")
		)
		(fp_line
			(start -0.67945 -0.305054)
			(end -0.12065 -0.305054)
			(stroke
				(width 0.1)
				(type default)
			)
			(layer "F.Fab")
		)
		(pad "1" smd circle
			(at -0.40005 0 180)
			(size 0 0)
			(layers "F.Cu" "F.Mask" "F.Paste")
			(net "SMB_BIC_I2C6_MUX_FRU_R_SDA")
		)
		(pad "2" smd circle
			(at 0.40005 0 180)
			(size 0 0)
			(layers "F.Cu" "F.Mask" "F.Paste")
			(net "SMB_BMC_FRU_SDA")
		)
	)
	(footprint ""
		(layer "F.Cu")
		(at 438.497218 -309.0418 135)
		(property "Reference" "R1452"
			(at 0 0 135)
			(layer "F.SilkS")
			(hide yes)
			(effects
				(font
					(size 1.27 1.27)
				)
			)
		)
		(property "Value" ""
			(at 0 0 135)
			(layer "F.Fab")
			(effects
				(font
					(size 1.27 1.27)
				)
			)
		)
		(duplicate_pad_numbers_are_jumpers no)
		(fp_line
			(start 0.787389 -0.406267)
			(end 0.787389 0.406267)
			(stroke
				(width 0.1524)
				(type default)
			)
			(layer "F.SilkS")
		)
		(fp_line
			(start 0.787389 0.406267)
			(end -0.787389 0.406267)
			(stroke
				(width 0.1524)
				(type default)
			)
			(layer "F.SilkS")
		)
		(fp_line
			(start -0.787389 -0.406267)
			(end 0.787389 -0.406267)
			(stroke
				(width 0.1524)
				(type default)
			)
			(layer "F.SilkS")
		)
		(fp_line
			(start -0.787389 0.406267)
			(end -0.787389 -0.406267)
			(stroke
				(width 0.1524)
				(type default)
			)
			(layer "F.SilkS")
		)
		(fp_line
			(start 0.679446 -0.30479)
			(end 0.679446 0.30479)
			(stroke
				(width 0.1)
				(type default)
			)
			(layer "F.Fab")
		)
		(fp_line
			(start 0.120515 -0.30479)
			(end 0.679446 -0.30479)
			(stroke
				(width 0.1)
				(type default)
			)
			(layer "F.Fab")
		)
		(fp_line
			(start 0.120695 -0.279466)
			(end 0.120515 -0.30479)
			(stroke
				(width 0.1)
				(type default)
			)
			(layer "F.Fab")
		)
		(fp_line
			(start 0.679446 0.30479)
			(end 0.120515 0.30479)
			(stroke
				(width 0.1)
				(type default)
			)
			(layer "F.Fab")
		)
		(fp_line
			(start -0.120695 -0.304969)
			(end -0.120695 -0.279466)
			(stroke
				(width 0.1)
				(type default)
			)
			(layer "F.Fab")
		)
		(fp_line
			(start -0.120695 -0.279466)
			(end 0.120695 -0.279466)
			(stroke
				(width 0.1)
				(type default)
			)
			(layer "F.Fab")
		)
		(fp_line
			(start 0.120335 0.279466)
			(end -0.120695 0.279466)
			(stroke
				(width 0.1)
				(type default)
			)
			(layer "F.Fab")
		)
		(fp_line
			(start 0.120515 0.30479)
			(end 0.120335 0.279466)
			(stroke
				(width 0.1)
				(type default)
			)
			(layer "F.Fab")
		)
		(fp_line
			(start -0.679446 -0.305149)
			(end -0.120695 -0.304969)
			(stroke
				(width 0.1)
				(type default)
			)
			(layer "F.Fab")
		)
		(fp_line
			(start -0.120695 0.279466)
			(end -0.120515 0.30479)
			(stroke
				(width 0.1)
				(type default)
			)
			(layer "F.Fab")
		)
		(fp_line
			(start -0.120515 0.30479)
			(end -0.679446 0.30479)
			(stroke
				(width 0.1)
				(type default)
			)
			(layer "F.Fab")
		)
		(fp_line
			(start -0.679446 0.30479)
			(end -0.679446 -0.305149)
			(stroke
				(width 0.1)
				(type default)
			)
			(layer "F.Fab")
		)
		(pad "1" smd circle
			(at -0.40005 0 135)
			(size 0 0)
			(layers "F.Cu" "F.Mask" "F.Paste")
			(net "GND")
		)
		(pad "2" smd circle
			(at 0.40005 0 135)
			(size 0 0)
			(layers "F.Cu" "F.Mask" "F.Paste")
			(net "PEX3_SPARE2")
		)
	)
	(footprint ""
		(layer "F.Cu")
		(at 243.355114 -305.118262)
		(property "Reference" "PC251"
			(at 0 0 0)
			(layer "F.SilkS")
			(hide yes)
			(effects
				(font
					(size 1.27 1.27)
				)
			)
		)
		(property "Value" ""
			(at 0 0 0)
			(layer "F.Fab")
			(effects
				(font
					(size 1.27 1.27)
				)
			)
		)
		(duplicate_pad_numbers_are_jumpers no)
		(fp_line
			(start -0.7874 -0.4064)
			(end 0.7874 -0.4064)
			(stroke
				(width 0.1524)
				(type default)
			)
			(layer "F.SilkS")
		)
		(fp_line
			(start -0.7874 0.4064)
			(end -0.7874 -0.4064)
			(stroke
				(width 0.1524)
				(type default)
			)
			(layer "F.SilkS")
		)
		(fp_line
			(start 0.7874 -0.4064)
			(end 0.7874 0.4064)
			(stroke
				(width 0.1524)
				(type default)
			)
			(layer "F.SilkS")
		)
		(fp_line
			(start 0.7874 0.4064)
			(end -0.7874 0.4064)
			(stroke
				(width 0.1524)
				(type default)
			)
			(layer "F.SilkS")
		)
		(fp_line
			(start -0.67945 -0.305054)
			(end -0.12065 -0.305054)
			(stroke
				(width 0.1)
				(type default)
			)
			(layer "F.Fab")
		)
		(fp_line
			(start -0.67945 0.3048)
			(end -0.67945 -0.305054)
			(stroke
				(width 0.1)
				(type default)
			)
			(layer "F.Fab")
		)
		(fp_line
			(start -0.12065 -0.305054)
			(end -0.12065 -0.2794)
			(stroke
				(width 0.1)
				(type default)
			)
			(layer "F.Fab")
		)
		(fp_line
			(start -0.12065 -0.2794)
			(end 0.12065 -0.2794)
			(stroke
				(width 0.1)
				(type default)
			)
			(layer "F.Fab")
		)
		(fp_line
			(start -0.12065 0.2794)
			(end -0.12065 0.3048)
			(stroke
				(width 0.1)
				(type default)
			)
			(layer "F.Fab")
		)
		(fp_line
			(start -0.12065 0.3048)
			(end -0.67945 0.3048)
			(stroke
				(width 0.1)
				(type default)
			)
			(layer "F.Fab")
		)
		(fp_line
			(start 0.120396 0.2794)
			(end -0.12065 0.2794)
			(stroke
				(width 0.1)
				(type default)
			)
			(layer "F.Fab")
		)
		(fp_line
			(start 0.120396 0.3048)
			(end 0.120396 0.2794)
			(stroke
				(width 0.1)
				(type default)
			)
			(layer "F.Fab")
		)
		(fp_line
			(start 0.12065 -0.3048)
			(end 0.67945 -0.3048)
			(stroke
				(width 0.1)
				(type default)
			)
			(layer "F.Fab")
		)
		(fp_line
			(start 0.12065 -0.2794)
			(end 0.12065 -0.3048)
			(stroke
				(width 0.1)
				(type default)
			)
			(layer "F.Fab")
		)
		(fp_line
			(start 0.67945 -0.3048)
			(end 0.67945 0.3048)
			(stroke
				(width 0.1)
				(type default)
			)
			(layer "F.Fab")
		)
		(fp_line
			(start 0.67945 0.3048)
			(end 0.120396 0.3048)
			(stroke
				(width 0.1)
				(type default)
			)
			(layer "F.Fab")
		)
		(pad "1" smd circle
			(at -0.40005 0)
			(size 0 0)
			(layers "F.Cu" "F.Mask" "F.Paste")
			(net "SW_P1V25_PEX2_BT")
		)
		(pad "2" smd circle
			(at 0.40005 0)
			(size 0 0)
			(layers "F.Cu" "F.Mask" "F.Paste")
			(net "SW_P1V25_PEX2_PH")
		)
	)
	(footprint ""
		(layer "F.Cu")
		(at 214.773002 -22.867366 90)
		(property "Reference" "C3921"
			(at 0 0 90)
			(layer "F.SilkS")
			(hide yes)
			(effects
				(font
					(size 1.27 1.27)
				)
			)
		)
		(property "Value" ""
			(at 0 0 90)
			(layer "F.Fab")
			(effects
				(font
					(size 1.27 1.27)
				)
			)
		)
		(duplicate_pad_numbers_are_jumpers no)
		(fp_line
			(start 0.7874 -0.4064)
			(end 0.7874 0.4064)
			(stroke
				(width 0.1524)
				(type default)
			)
			(layer "F.SilkS")
		)
		(fp_line
			(start -0.7874 -0.4064)
			(end 0.7874 -0.4064)
			(stroke
				(width 0.1524)
				(type default)
			)
			(layer "F.SilkS")
		)
		(fp_line
			(start 0.7874 0.4064)
			(end -0.7874 0.4064)
			(stroke
				(width 0.1524)
				(type default)
			)
			(layer "F.SilkS")
		)
		(fp_line
			(start -0.7874 0.4064)
			(end -0.7874 -0.4064)
			(stroke
				(width 0.1524)
				(type default)
			)
			(layer "F.SilkS")
		)
		(fp_line
			(start -0.12065 -0.305054)
			(end -0.12065 -0.2794)
			(stroke
				(width 0.1)
				(type default)
			)
			(layer "F.Fab")
		)
		(fp_line
			(start -0.67945 -0.305054)
			(end -0.12065 -0.305054)
			(stroke
				(width 0.1)
				(type default)
			)
			(layer "F.Fab")
		)
		(fp_line
			(start 0.67945 -0.3048)
			(end 0.67945 0.3048)
			(stroke
				(width 0.1)
				(type default)
			)
			(layer "F.Fab")
		)
		(fp_line
			(start 0.12065 -0.3048)
			(end 0.67945 -0.3048)
			(stroke
				(width 0.1)
				(type default)
			)
			(layer "F.Fab")
		)
		(fp_line
			(start 0.12065 -0.2794)
			(end 0.12065 -0.3048)
			(stroke
				(width 0.1)
				(type default)
			)
			(layer "F.Fab")
		)
		(fp_line
			(start -0.12065 -0.2794)
			(end 0.12065 -0.2794)
			(stroke
				(width 0.1)
				(type default)
			)
			(layer "F.Fab")
		)
		(fp_line
			(start 0.120396 0.2794)
			(end -0.12065 0.2794)
			(stroke
				(width 0.1)
				(type default)
			)
			(layer "F.Fab")
		)
		(fp_line
			(start -0.12065 0.2794)
			(end -0.12065 0.3048)
			(stroke
				(width 0.1)
				(type default)
			)
			(layer "F.Fab")
		)
		(fp_line
			(start 0.67945 0.3048)
			(end 0.120396 0.3048)
			(stroke
				(width 0.1)
				(type default)
			)
			(layer "F.Fab")
		)
		(fp_line
			(start 0.120396 0.3048)
			(end 0.120396 0.2794)
			(stroke
				(width 0.1)
				(type default)
			)
			(layer "F.Fab")
		)
		(fp_line
			(start -0.12065 0.3048)
			(end -0.67945 0.3048)
			(stroke
				(width 0.1)
				(type default)
			)
			(layer "F.Fab")
		)
		(fp_line
			(start -0.67945 0.3048)
			(end -0.67945 -0.305054)
			(stroke
				(width 0.1)
				(type default)
			)
			(layer "F.Fab")
		)
		(pad "1" smd circle
			(at -0.40005 0 90)
			(size 0 0)
			(layers "F.Cu" "F.Mask" "F.Paste")
			(net "P12V_SSD7")
		)
		(pad "2" smd circle
			(at 0.40005 0 90)
			(size 0 0)
			(layers "F.Cu" "F.Mask" "F.Paste")
			(net "GND")
		)
	)
	(footprint ""
		(layer "F.Cu")
		(at 167.164512 -29.079952 180)
		(property "Reference" "R6203"
			(at 0 0 180)
			(layer "F.SilkS")
			(hide yes)
			(effects
				(font
					(size 1.27 1.27)
				)
			)
		)
		(property "Value" ""
			(at 0 0 180)
			(layer "F.Fab")
			(effects
				(font
					(size 1.27 1.27)
				)
			)
		)
		(duplicate_pad_numbers_are_jumpers no)
		(fp_line
			(start 0.7874 0.4064)
			(end -0.7874 0.4064)
			(stroke
				(width 0.1524)
				(type default)
			)
			(layer "F.SilkS")
		)
		(fp_line
			(start 0.7874 -0.4064)
			(end 0.7874 0.4064)
			(stroke
				(width 0.1524)
				(type default)
			)
			(layer "F.SilkS")
		)
		(fp_line
			(start -0.7874 0.4064)
			(end -0.7874 -0.4064)
			(stroke
				(width 0.1524)
				(type default)
			)
			(layer "F.SilkS")
		)
		(fp_line
			(start -0.7874 -0.4064)
			(end 0.7874 -0.4064)
			(stroke
				(width 0.1524)
				(type default)
			)
			(layer "F.SilkS")
		)
		(fp_line
			(start 0.67945 0.3048)
			(end 0.120396 0.3048)
			(stroke
				(width 0.1)
				(type default)
			)
			(layer "F.Fab")
		)
		(fp_line
			(start 0.67945 -0.3048)
			(end 0.67945 0.3048)
			(stroke
				(width 0.1)
				(type default)
			)
			(layer "F.Fab")
		)
		(fp_line
			(start 0.12065 -0.2794)
			(end 0.12065 -0.3048)
			(stroke
				(width 0.1)
				(type default)
			)
			(layer "F.Fab")
		)
		(fp_line
			(start 0.12065 -0.3048)
			(end 0.67945 -0.3048)
			(stroke
				(width 0.1)
				(type default)
			)
			(layer "F.Fab")
		)
		(fp_line
			(start 0.120396 0.3048)
			(end 0.120396 0.2794)
			(stroke
				(width 0.1)
				(type default)
			)
			(layer "F.Fab")
		)
		(fp_line
			(start 0.120396 0.2794)
			(end -0.12065 0.2794)
			(stroke
				(width 0.1)
				(type default)
			)
			(layer "F.Fab")
		)
		(fp_line
			(start -0.12065 0.3048)
			(end -0.67945 0.3048)
			(stroke
				(width 0.1)
				(type default)
			)
			(layer "F.Fab")
		)
		(fp_line
			(start -0.12065 0.2794)
			(end -0.12065 0.3048)
			(stroke
				(width 0.1)
				(type default)
			)
			(layer "F.Fab")
		)
		(fp_line
			(start -0.12065 -0.2794)
			(end 0.12065 -0.2794)
			(stroke
				(width 0.1)
				(type default)
			)
			(layer "F.Fab")
		)
		(fp_line
			(start -0.12065 -0.305054)
			(end -0.12065 -0.2794)
			(stroke
				(width 0.1)
				(type default)
			)
			(layer "F.Fab")
		)
		(fp_line
			(start -0.67945 0.3048)
			(end -0.67945 -0.305054)
			(stroke
				(width 0.1)
				(type default)
			)
			(layer "F.Fab")
		)
		(fp_line
			(start -0.67945 -0.305054)
			(end -0.12065 -0.305054)
			(stroke
				(width 0.1)
				(type default)
			)
			(layer "F.Fab")
		)
		(pad "1" smd circle
			(at -0.40005 0 180)
			(size 0 0)
			(layers "F.Cu" "F.Mask" "F.Paste")
			(net "GND")
		)
		(pad "2" smd circle
			(at 0.40005 0 180)
			(size 0 0)
			(layers "F.Cu" "F.Mask" "F.Paste")
			(net "SSD5_PWRDIS_R")
		)
	)
	(footprint ""
		(layer "F.Cu")
		(at 430.961546 -156.111194 180)
		(property "Reference" "C634"
			(at 0 0 180)
			(layer "F.SilkS")
			(hide yes)
			(effects
				(font
					(size 1.27 1.27)
				)
			)
		)
		(property "Value" ""
			(at 0 0 180)
			(layer "F.Fab")
			(effects
				(font
					(size 1.27 1.27)
				)
			)
		)
		(duplicate_pad_numbers_are_jumpers no)
		(fp_line
			(start 0.299974 0.150114)
			(end -0.299974 0.150114)
			(stroke
				(width 0.1)
				(type default)
			)
			(layer "F.Fab")
		)
		(fp_line
			(start 0.299974 -0.150114)
			(end 0.299974 0.150114)
			(stroke
				(width 0.1)
				(type default)
			)
			(layer "F.Fab")
		)
		(fp_line
			(start -0.299974 0.150114)
			(end -0.299974 -0.150114)
			(stroke
				(width 0.1)
				(type default)
			)
			(layer "F.Fab")
		)
		(fp_line
			(start -0.299974 -0.150114)
			(end 0.299974 -0.150114)
			(stroke
				(width 0.1)
				(type default)
			)
			(layer "F.Fab")
		)
		(pad "1" smd rect
			(at -0.2667 0 180)
			(size 0.3048 0.381)
			(layers "F.Cu" "F.Mask" "F.Paste")
			(net "P5E_PEX3_STN0_TX_DP<15>")
		)
		(pad "2" smd rect
			(at 0.2667 0 180)
			(size 0.3048 0.381)
			(layers "F.Cu" "F.Mask" "F.Paste")
			(net "P5E_PEX3_STN0_TX_C_DP<15>")
		)
	)
	(footprint ""
		(layer "F.Cu")
		(at 355.300788 -293.5351 90)
		(property "Reference" "PL15"
			(at -4.976876 14.56182 90)
			(unlocked yes)
			(layer "F.SilkS")
			(effects
				(font
					(size 0.7874 0.5842)
					(thickness 0.1524)
				)
				(justify left)
			)
		)
		(property "Value" ""
			(at 0 0 90)
			(layer "F.Fab")
			(effects
				(font
					(size 1.27 1.27)
				)
			)
		)
		(duplicate_pad_numbers_are_jumpers no)
		(fp_line
			(start 4.800092 -3.199892)
			(end 4.800092 -1.6764)
			(stroke
				(width 0.1524)
				(type default)
			)
			(layer "F.SilkS")
		)
		(fp_line
			(start -4.800092 -3.199892)
			(end 4.800092 -3.199892)
			(stroke
				(width 0.1524)
				(type default)
			)
			(layer "F.SilkS")
		)
		(fp_line
			(start -4.800092 -1.6764)
			(end -4.800092 -3.199892)
			(stroke
				(width 0.1524)
				(type default)
			)
			(layer "F.SilkS")
		)
		(fp_line
			(start 4.800092 1.6764)
			(end 4.800092 3.199892)
			(stroke
				(width 0.1524)
				(type default)
			)
			(layer "F.SilkS")
		)
		(fp_line
			(start 4.800092 3.199892)
			(end -4.800092 3.199892)
			(stroke
				(width 0.1524)
				(type default)
			)
			(layer "F.SilkS")
		)
		(fp_line
			(start -4.800092 3.199892)
			(end -4.800092 1.6764)
			(stroke
				(width 0.1524)
				(type default)
			)
			(layer "F.SilkS")
		)
		(fp_line
			(start 4.800092 -3.199892)
			(end 4.800092 3.199892)
			(stroke
				(width 0.1)
				(type default)
			)
			(layer "F.Fab")
		)
		(fp_line
			(start -4.800092 -3.199892)
			(end 4.800092 -3.199892)
			(stroke
				(width 0.1)
				(type default)
			)
			(layer "F.Fab")
		)
		(fp_line
			(start 4.800092 3.199892)
			(end -4.800092 3.199892)
			(stroke
				(width 0.1)
				(type default)
			)
			(layer "F.Fab")
		)
		(fp_line
			(start -4.800092 3.199892)
			(end -4.800092 -3.199892)
			(stroke
				(width 0.1)
				(type default)
			)
			(layer "F.Fab")
		)
		(pad "1" smd rect
			(at -3.074924 0 180)
			(size 3.0988 3.3528)
			(layers "F.Cu" "F.Mask" "F.Paste")
			(net "SW_P0V8_PEX3_PH1")
		)
		(pad "2" smd rect
			(at 3.074924 0 180)
			(size 3.0988 3.3528)
			(layers "F.Cu" "F.Mask" "F.Paste")
			(net "P0V8_PEX3")
		)
	)
)
